(kicad_pcb
	(version 20260206)
	(generator "pcbnew")
	(generator_version "10.0")
	(general
		(thickness 1.6)
		(legacy_teardrops no)
	)
	(paper "A4")
	(title_block
		(title "Wiwynn_Tioga_Pass_MB.brd")
		(comment 1 "Tioga Pass / footprints 822-829 of 4770")
	)
	(layers
		(0 "F.Cu" signal "TOP")
		(4 "In1.Cu" signal "L2GND")
		(6 "In2.Cu" signal "L3")
		(8 "In3.Cu" signal "L4GND")
		(10 "In4.Cu" signal "L5")
		(12 "In5.Cu" signal "L6GND")
		(14 "In6.Cu" signal "L7VCC")
		(16 "In7.Cu" signal "L8VCC")
		(18 "In8.Cu" signal "L9GND")
		(20 "In9.Cu" signal "L10")
		(22 "In10.Cu" signal "L11GND")
		(24 "In11.Cu" signal "L12")
		(26 "In12.Cu" signal "L13GND")
		(2 "B.Cu" signal "BOTTOM")
		(9 "F.Adhes" user "F.Adhesive")
		(11 "B.Adhes" user "B.Adhesive")
		(13 "F.Paste" user "Package Geometry/Pastemask Top")
		(15 "B.Paste" user "Package Geometry/Pastemask Bottom")
		(5 "F.SilkS" user "Ref Des/Silkscreen Top")
		(7 "B.SilkS" user "Ref Des/Silkscreen Bottom")
		(1 "F.Mask" user "Board Geometry/Soldermask Top")
		(3 "B.Mask" user "Board Geometry/Soldermask Bottom")
		(17 "Dwgs.User" user "User.Drawings")
		(19 "Cmts.User" user "User.Comments")
		(21 "Eco1.User" user "User.Eco1")
		(23 "Eco2.User" user "User.Eco2")
		(25 "Edge.Cuts" user "Board Geometry/Outline")
		(27 "Margin" user)
		(31 "F.CrtYd" user "Package Geometry/Place Bound Top")
		(29 "B.CrtYd" user "Package Geometry/Place Bound Bottom")
		(35 "F.Fab" user "Ref Des/Assembly Top")
		(33 "B.Fab" user "Ref Des/Assembly Bottom")
	)
	(footprint ""
		(layer "F.Cu")
		(at 491.0455 -41.0464 90)
		(property "Reference" "R9E22"
			(at 0 0 90)
			(layer "F.SilkS")
			(hide yes)
			(effects
				(font
					(size 1.27 1.27)
				)
			)
		)
		(property "Value" ""
			(at 0 0 90)
			(layer "F.Fab")
			(effects
				(font
					(size 1.27 1.27)
				)
			)
		)
		(duplicate_pad_numbers_are_jumpers no)
		(fp_poly
			(pts
				(xy -0.2794 -0.1016) (xy 0.2794 -0.1016) (xy 0.2794 0.9906) (xy -0.2794 0.9906)
			)
			(stroke
				(width 0)
				(type default)
			)
			(fill no)
			(layer "F.CrtYd")
		)
		(fp_line
			(start 0.2794 -0.1016)
			(end -0.2794 -0.1016)
			(stroke
				(width 0.1)
				(type default)
			)
			(layer "F.Fab")
		)
		(fp_line
			(start -0.2794 -0.1016)
			(end -0.2794 0.9906)
			(stroke
				(width 0.1)
				(type default)
			)
			(layer "F.Fab")
		)
		(fp_line
			(start 0.2794 0.9906)
			(end 0.2794 -0.1016)
			(stroke
				(width 0.1)
				(type default)
			)
			(layer "F.Fab")
		)
		(fp_line
			(start -0.2794 0.9906)
			(end 0.2794 0.9906)
			(stroke
				(width 0.1)
				(type default)
			)
			(layer "F.Fab")
		)
		(pad "1" smd rect
			(at 0 0 90)
			(size 0.508 0.508)
			(layers "F.Cu" "F.Mask" "F.Paste")
			(net "PU_JTAG_SPRV_TDO")
		)
		(pad "2" smd rect
			(at 0 0.889 90)
			(size 0.508 0.508)
			(layers "F.Cu" "F.Mask" "F.Paste")
			(net "P3V3_STBY")
		)
		(zone
			(layer "F.Cu")
			(hatch none 0.5)
			(connect_pads
				(clearance 0)
			)
			(min_thickness 0.25)
			(keepout
				(tracks allowed)
				(vias not_allowed)
				(pads allowed)
				(copperpour not_allowed)
				(footprints allowed)
			)
			(placement
				(enabled no)
				(sheetname "")
			)
			(fill
				(thermal_gap 0.5)
				(thermal_bridge_width 0.5)
				(island_removal_mode 0)
			)
			(polygon
				(pts
					(xy 491.2995 -40.7924) (xy 491.2995 -41.3004) (xy 491.6805 -41.3004) (xy 491.6805 -40.7924)
				)
			)
		)
		(zone
			(layer "F.Cu")
			(hatch none 0.5)
			(connect_pads
				(clearance 0)
			)
			(min_thickness 0.25)
			(keepout
				(tracks not_allowed)
				(vias allowed)
				(pads allowed)
				(copperpour not_allowed)
				(footprints allowed)
			)
			(placement
				(enabled no)
				(sheetname "")
			)
			(fill
				(thermal_gap 0.5)
				(thermal_bridge_width 0.5)
				(island_removal_mode 0)
			)
			(polygon
				(pts
					(xy 491.6805 -40.7924) (xy 491.6805 -41.3004) (xy 491.2995 -41.3004) (xy 491.2995 -40.7924)
				)
			)
		)
	)
	(footprint ""
		(layer "F.Cu")
		(at 113.1824 -69.4182 90)
		(property "Reference" "R3D25"
			(at 0 0 90)
			(layer "F.SilkS")
			(hide yes)
			(effects
				(font
					(size 1.27 1.27)
				)
			)
		)
		(property "Value" ""
			(at 0 0 90)
			(layer "F.Fab")
			(effects
				(font
					(size 1.27 1.27)
				)
			)
		)
		(duplicate_pad_numbers_are_jumpers no)
		(fp_poly
			(pts
				(xy -0.2794 -0.1016) (xy 0.2794 -0.1016) (xy 0.2794 0.9906) (xy -0.2794 0.9906)
			)
			(stroke
				(width 0)
				(type default)
			)
			(fill no)
			(layer "F.CrtYd")
		)
		(fp_line
			(start 0.2794 -0.1016)
			(end -0.2794 -0.1016)
			(stroke
				(width 0.1)
				(type default)
			)
			(layer "F.Fab")
		)
		(fp_line
			(start -0.2794 -0.1016)
			(end -0.2794 0.9906)
			(stroke
				(width 0.1)
				(type default)
			)
			(layer "F.Fab")
		)
		(fp_line
			(start 0.2794 0.9906)
			(end 0.2794 -0.1016)
			(stroke
				(width 0.1)
				(type default)
			)
			(layer "F.Fab")
		)
		(fp_line
			(start -0.2794 0.9906)
			(end 0.2794 0.9906)
			(stroke
				(width 0.1)
				(type default)
			)
			(layer "F.Fab")
		)
		(pad "1" smd rect
			(at 0 0 90)
			(size 0.508 0.508)
			(layers "F.Cu" "F.Mask" "F.Paste")
			(net "GND")
		)
		(pad "2" smd rect
			(at 0 0.889 90)
			(size 0.508 0.508)
			(layers "F.Cu" "F.Mask" "F.Paste")
			(net "PD_CPU1_EAR_N")
		)
		(zone
			(layer "F.Cu")
			(hatch none 0.5)
			(connect_pads
				(clearance 0)
			)
			(min_thickness 0.25)
			(keepout
				(tracks allowed)
				(vias not_allowed)
				(pads allowed)
				(copperpour not_allowed)
				(footprints allowed)
			)
			(placement
				(enabled no)
				(sheetname "")
			)
			(fill
				(thermal_gap 0.5)
				(thermal_bridge_width 0.5)
				(island_removal_mode 0)
			)
			(polygon
				(pts
					(xy 113.4364 -69.1642) (xy 113.4364 -69.6722) (xy 113.8174 -69.6722) (xy 113.8174 -69.1642)
				)
			)
		)
		(zone
			(layer "F.Cu")
			(hatch none 0.5)
			(connect_pads
				(clearance 0)
			)
			(min_thickness 0.25)
			(keepout
				(tracks not_allowed)
				(vias allowed)
				(pads allowed)
				(copperpour not_allowed)
				(footprints allowed)
			)
			(placement
				(enabled no)
				(sheetname "")
			)
			(fill
				(thermal_gap 0.5)
				(thermal_bridge_width 0.5)
				(island_removal_mode 0)
			)
			(polygon
				(pts
					(xy 113.8174 -69.1642) (xy 113.8174 -69.6722) (xy 113.4364 -69.6722) (xy 113.4364 -69.1642)
				)
			)
		)
	)
	(footprint ""
		(layer "F.Cu")
		(at 39.322756 -107.355132 -90)
		(property "Reference" "R9N1"
			(at 0 0 270)
			(layer "F.SilkS")
			(hide yes)
			(effects
				(font
					(size 1.27 1.27)
				)
			)
		)
		(property "Value" ""
			(at 0 0 270)
			(layer "F.Fab")
			(effects
				(font
					(size 1.27 1.27)
				)
			)
		)
		(duplicate_pad_numbers_are_jumpers no)
		(fp_poly
			(pts
				(xy -0.2794 -0.1016) (xy 0.2794 -0.1016) (xy 0.2794 0.9906) (xy -0.2794 0.9906)
			)
			(stroke
				(width 0)
				(type default)
			)
			(fill no)
			(layer "F.CrtYd")
		)
		(fp_line
			(start -0.2794 0.9906)
			(end 0.2794 0.9906)
			(stroke
				(width 0.1)
				(type default)
			)
			(layer "F.Fab")
		)
		(fp_line
			(start 0.2794 0.9906)
			(end 0.2794 -0.1016)
			(stroke
				(width 0.1)
				(type default)
			)
			(layer "F.Fab")
		)
		(fp_line
			(start -0.2794 -0.1016)
			(end -0.2794 0.9906)
			(stroke
				(width 0.1)
				(type default)
			)
			(layer "F.Fab")
		)
		(fp_line
			(start 0.2794 -0.1016)
			(end -0.2794 -0.1016)
			(stroke
				(width 0.1)
				(type default)
			)
			(layer "F.Fab")
		)
		(pad "1" smd rect
			(at 0 0 270)
			(size 0.508 0.508)
			(layers "F.Cu" "F.Mask" "F.Paste")
			(net "PVCCIO_CPU1")
		)
		(pad "2" smd rect
			(at 0 0.889 270)
			(size 0.508 0.508)
			(layers "F.Cu" "F.Mask" "F.Paste")
			(net "SVID_ALERT1_CPU1_R_N")
		)
		(zone
			(layer "F.Cu")
			(hatch none 0.5)
			(connect_pads
				(clearance 0)
			)
			(min_thickness 0.25)
			(keepout
				(tracks not_allowed)
				(vias allowed)
				(pads allowed)
				(copperpour not_allowed)
				(footprints allowed)
			)
			(placement
				(enabled no)
				(sheetname "")
			)
			(fill
				(thermal_gap 0.5)
				(thermal_bridge_width 0.5)
				(island_removal_mode 0)
			)
			(polygon
				(pts
					(xy 38.687756 -107.609132) (xy 38.687756 -107.101132) (xy 39.068756 -107.101132) (xy 39.068756 -107.609132)
				)
			)
		)
		(zone
			(layer "F.Cu")
			(hatch none 0.5)
			(connect_pads
				(clearance 0)
			)
			(min_thickness 0.25)
			(keepout
				(tracks allowed)
				(vias not_allowed)
				(pads allowed)
				(copperpour not_allowed)
				(footprints allowed)
			)
			(placement
				(enabled no)
				(sheetname "")
			)
			(fill
				(thermal_gap 0.5)
				(thermal_bridge_width 0.5)
				(island_removal_mode 0)
			)
			(polygon
				(pts
					(xy 39.068756 -107.609132) (xy 39.068756 -107.101132) (xy 38.687756 -107.101132) (xy 38.687756 -107.609132)
				)
			)
		)
	)
	(footprint ""
		(layer "F.Cu")
		(at 372.528338 -146.561048 180)
		(property "Reference" "CT65"
			(at -0.8382 -0.67818 180)
			(unlocked yes)
			(layer "F.SilkS")
			(effects
				(font
					(size 0.4064 0.254)
					(thickness 0.1524)
				)
				(justify left)
			)
		)
		(property "Value" ""
			(at 0 0 180)
			(layer "F.Fab")
			(effects
				(font
					(size 1.27 1.27)
				)
			)
		)
		(duplicate_pad_numbers_are_jumpers no)
		(fp_poly
			(pts
				(xy 0.3048 -0.1016) (xy 0.3048 0.9906) (xy -0.3048 0.9906) (xy -0.3048 -0.1016)
			)
			(stroke
				(width 0)
				(type default)
			)
			(fill no)
			(layer "F.CrtYd")
		)
		(fp_line
			(start 0.3048 0.9906)
			(end 0.3048 -0.1016)
			(stroke
				(width 0.1)
				(type default)
			)
			(layer "F.Fab")
		)
		(fp_line
			(start 0.3048 -0.1016)
			(end -0.3048 -0.1016)
			(stroke
				(width 0.1)
				(type default)
			)
			(layer "F.Fab")
		)
		(fp_line
			(start -0.3048 0.9906)
			(end 0.3048 0.9906)
			(stroke
				(width 0.1)
				(type default)
			)
			(layer "F.Fab")
		)
		(fp_line
			(start -0.3048 -0.1016)
			(end -0.3048 0.9906)
			(stroke
				(width 0.1)
				(type default)
			)
			(layer "F.Fab")
		)
		(pad "1" smd rect
			(at 0 0 180)
			(size 0.508 0.508)
			(layers "F.Cu" "F.Mask" "F.Paste")
			(net "VR_PVNN_PCH_PH1_PHASE_SW")
		)
		(pad "2" smd rect
			(at 0 0.889 180)
			(size 0.508 0.508)
			(layers "F.Cu" "F.Mask" "F.Paste")
			(net "VR_PVNN_PCH_PH1_PHASE_SW_RC")
		)
		(zone
			(layer "F.Cu")
			(hatch none 0.5)
			(connect_pads
				(clearance 0)
			)
			(min_thickness 0.25)
			(keepout
				(tracks not_allowed)
				(vias allowed)
				(pads allowed)
				(copperpour not_allowed)
				(footprints allowed)
			)
			(placement
				(enabled no)
				(sheetname "")
			)
			(fill
				(thermal_gap 0.5)
				(thermal_bridge_width 0.5)
				(island_removal_mode 0)
			)
			(polygon
				(pts
					(xy 372.782338 -147.196048) (xy 372.274338 -147.196048) (xy 372.274338 -146.815048) (xy 372.782338 -146.815048)
				)
			)
		)
		(zone
			(layer "F.Cu")
			(hatch none 0.5)
			(connect_pads
				(clearance 0)
			)
			(min_thickness 0.25)
			(keepout
				(tracks allowed)
				(vias not_allowed)
				(pads allowed)
				(copperpour not_allowed)
				(footprints allowed)
			)
			(placement
				(enabled no)
				(sheetname "")
			)
			(fill
				(thermal_gap 0.5)
				(thermal_bridge_width 0.5)
				(island_removal_mode 0)
			)
			(polygon
				(pts
					(xy 372.782338 -146.815048) (xy 372.274338 -146.815048) (xy 372.274338 -147.196048) (xy 372.782338 -147.196048)
				)
			)
		)
	)
	(footprint ""
		(layer "F.Cu")
		(at 320.194432 -3.302 90)
		(property "Reference" "C6G5"
			(at 0 0 90)
			(layer "F.SilkS")
			(hide yes)
			(effects
				(font
					(size 1.27 1.27)
				)
			)
		)
		(property "Value" ""
			(at 0 0 90)
			(layer "F.Fab")
			(effects
				(font
					(size 1.27 1.27)
				)
			)
		)
		(duplicate_pad_numbers_are_jumpers no)
		(fp_poly
			(pts
				(xy -0.4953 -0.2032) (xy 0.4953 -0.2032) (xy 0.4953 1.6002) (xy -0.4953 1.6002)
			)
			(stroke
				(width 0)
				(type default)
			)
			(fill no)
			(layer "F.CrtYd")
		)
		(fp_line
			(start 0.4953 -0.2032)
			(end 0.4953 1.6002)
			(stroke
				(width 0.1)
				(type default)
			)
			(layer "F.Fab")
		)
		(fp_line
			(start -0.4953 -0.2032)
			(end 0.4953 -0.2032)
			(stroke
				(width 0.1)
				(type default)
			)
			(layer "F.Fab")
		)
		(fp_line
			(start 0.4953 1.6002)
			(end -0.4953 1.6002)
			(stroke
				(width 0.1)
				(type default)
			)
			(layer "F.Fab")
		)
		(fp_line
			(start -0.4953 1.6002)
			(end -0.4953 -0.2032)
			(stroke
				(width 0.1)
				(type default)
			)
			(layer "F.Fab")
		)
		(pad "1" smd rect
			(at 0 0 90)
			(size 0.762 0.889)
			(layers "F.Cu" "F.Mask" "F.Paste")
			(net "PVPP_ABC")
		)
		(pad "2" smd rect
			(at 0 1.397 90)
			(size 0.762 0.889)
			(layers "F.Cu" "F.Mask" "F.Paste")
			(net "GND")
		)
		(zone
			(layer "F.Cu")
			(hatch none 0.5)
			(connect_pads
				(clearance 0)
			)
			(min_thickness 0.25)
			(keepout
				(tracks not_allowed)
				(vias allowed)
				(pads allowed)
				(copperpour not_allowed)
				(footprints allowed)
			)
			(placement
				(enabled no)
				(sheetname "")
			)
			(fill
				(thermal_gap 0.5)
				(thermal_bridge_width 0.5)
				(island_removal_mode 0)
			)
			(polygon
				(pts
					(xy 320.638932 -2.921) (xy 320.638932 -3.683) (xy 321.146932 -3.683) (xy 321.146932 -2.921)
				)
			)
		)
	)
	(footprint ""
		(layer "F.Cu")
		(at 438.833006 -41.663874 180)
		(property "Reference" "R25W21"
			(at 0 0 180)
			(layer "F.SilkS")
			(hide yes)
			(effects
				(font
					(size 1.27 1.27)
				)
			)
		)
		(property "Value" "*"
			(at 0.064008 -4.108196 180)
			(unlocked yes)
			(layer "F.Fab")
			(hide yes)
			(effects
				(font
					(size 1.27 1.016)
					(thickness 0.1524)
				)
			)
		)
		(property "Device Type" "120R2F-GP_RCL_GP-120R2F-GP,64.A"
			(at 0.064008 -5.632196 180)
			(unlocked yes)
			(layer "F.Fab")
			(hide yes)
			(effects
				(font
					(size 1.27 1.016)
					(thickness 0.1524)
				)
			)
		)
		(duplicate_pad_numbers_are_jumpers no)
		(fp_line
			(start 0.508 -0.9398)
			(end -0.508 -0.9398)
			(stroke
				(width 0.1524)
				(type default)
			)
			(layer "F.SilkS")
		)
		(fp_line
			(start -0.508 -0.9398)
			(end -0.508 0.9398)
			(stroke
				(width 0.1524)
				(type default)
			)
			(layer "F.SilkS")
		)
		(fp_rect
			(start -0.508 0.9398)
			(end 0.508 -0.9398)
			(stroke
				(width 0)
				(type default)
			)
			(fill no)
			(layer "F.CrtYd")
		)
		(fp_rect
			(start -0.508 0.9398)
			(end 0.508 -0.9398)
			(stroke
				(width 0)
				(type default)
			)
			(fill no)
			(layer "F.Fab")
		)
		(pad "1" smd custom
			(at 0 -0.4445 180)
			(size 0.1397 0.1397)
			(layers "F.Cu" "F.Mask" "F.Paste")
			(net "GND")
			(options
				(clearance outline)
				(anchor circle)
			)
			(primitives
				(gr_poly
					(pts
						(arc
							(start -0.1778 -0.2794)
							(mid -0.249642 -0.249642)
							(end -0.2794 -0.1778)
						)
						(arc
							(start -0.2794 0.1778)
							(mid -0.249642 0.249642)
							(end -0.1778 0.2794)
						)
						(arc
							(start 0.1778 0.2794)
							(mid 0.249642 0.249642)
							(end 0.2794 0.1778)
						)
						(arc
							(start 0.2794 -0.1778)
							(mid 0.249642 -0.249642)
							(end 0.1778 -0.2794)
						)
					)
					(width 0)
					(fill yes)
				)
			)
		)
		(pad "2" smd custom
			(at 0 0.4445 180)
			(size 0.1397 0.1397)
			(layers "F.Cu" "F.Mask" "F.Paste")
			(net "BMC_M_A9")
			(options
				(clearance outline)
				(anchor circle)
			)
			(primitives
				(gr_poly
					(pts
						(arc
							(start -0.1778 -0.2794)
							(mid -0.249642 -0.249642)
							(end -0.2794 -0.1778)
						)
						(arc
							(start -0.2794 0.1778)
							(mid -0.249642 0.249642)
							(end -0.1778 0.2794)
						)
						(arc
							(start 0.1778 0.2794)
							(mid 0.249642 0.249642)
							(end 0.2794 0.1778)
						)
						(arc
							(start 0.2794 -0.1778)
							(mid 0.249642 -0.249642)
							(end 0.1778 -0.2794)
						)
					)
					(width 0)
					(fill yes)
				)
			)
		)
	)
	(footprint ""
		(layer "F.Cu")
		(at 261.942072 -73.318116)
		(property "Reference" "C5D42"
			(at 0 0 0)
			(layer "F.SilkS")
			(hide yes)
			(effects
				(font
					(size 1.27 1.27)
				)
			)
		)
		(property "Value" ""
			(at 0 0 0)
			(layer "F.Fab")
			(effects
				(font
					(size 1.27 1.27)
				)
			)
		)
		(duplicate_pad_numbers_are_jumpers no)
		(fp_poly
			(pts
				(xy -0.4953 -0.2032) (xy 0.4953 -0.2032) (xy 0.4953 1.6002) (xy -0.4953 1.6002)
			)
			(stroke
				(width 0)
				(type default)
			)
			(fill no)
			(layer "F.CrtYd")
		)
		(fp_line
			(start -0.4953 -0.2032)
			(end 0.4953 -0.2032)
			(stroke
				(width 0.1)
				(type default)
			)
			(layer "F.Fab")
		)
		(fp_line
			(start -0.4953 1.6002)
			(end -0.4953 -0.2032)
			(stroke
				(width 0.1)
				(type default)
			)
			(layer "F.Fab")
		)
		(fp_line
			(start 0.4953 -0.2032)
			(end 0.4953 1.6002)
			(stroke
				(width 0.1)
				(type default)
			)
			(layer "F.Fab")
		)
		(fp_line
			(start 0.4953 1.6002)
			(end -0.4953 1.6002)
			(stroke
				(width 0.1)
				(type default)
			)
			(layer "F.Fab")
		)
		(pad "1" smd rect
			(at 0 0)
			(size 0.762 0.889)
			(layers "F.Cu" "F.Mask" "F.Paste")
			(net "PVCCIN_CPU0")
		)
		(pad "2" smd rect
			(at 0 1.397)
			(size 0.762 0.889)
			(layers "F.Cu" "F.Mask" "F.Paste")
			(net "GND")
		)
		(zone
			(layer "F.Cu")
			(hatch none 0.5)
			(connect_pads
				(clearance 0)
			)
			(min_thickness 0.25)
			(keepout
				(tracks not_allowed)
				(vias allowed)
				(pads allowed)
				(copperpour not_allowed)
				(footprints allowed)
			)
			(placement
				(enabled no)
				(sheetname "")
			)
			(fill
				(thermal_gap 0.5)
				(thermal_bridge_width 0.5)
				(island_removal_mode 0)
			)
			(polygon
				(pts
					(xy 261.561072 -72.873616) (xy 262.323072 -72.873616) (xy 262.323072 -72.365616) (xy 261.561072 -72.365616)
				)
			)
		)
	)
	(footprint ""
		(layer "F.Cu")
		(at 167.00627 -34.1503 90)
		(property "Reference" "C4F3"
			(at 0 0 90)
			(layer "F.SilkS")
			(hide yes)
			(effects
				(font
					(size 1.27 1.27)
				)
			)
		)
		(property "Value" ""
			(at 0 0 90)
			(layer "F.Fab")
			(effects
				(font
					(size 1.27 1.27)
				)
			)
		)
		(duplicate_pad_numbers_are_jumpers no)
		(fp_poly
			(pts
				(xy 0.3048 -0.1016) (xy 0.3048 0.9906) (xy -0.3048 0.9906) (xy -0.3048 -0.1016)
			)
			(stroke
				(width 0)
				(type default)
			)
			(fill no)
			(layer "F.CrtYd")
		)
		(fp_line
			(start 0.3048 -0.1016)
			(end -0.3048 -0.1016)
			(stroke
				(width 0.1)
				(type default)
			)
			(layer "F.Fab")
		)
		(fp_line
			(start -0.3048 -0.1016)
			(end -0.3048 0.9906)
			(stroke
				(width 0.1)
				(type default)
			)
			(layer "F.Fab")
		)
		(fp_line
			(start 0.3048 0.9906)
			(end 0.3048 -0.1016)
			(stroke
				(width 0.1)
				(type default)
			)
			(layer "F.Fab")
		)
		(fp_line
			(start -0.3048 0.9906)
			(end 0.3048 0.9906)
			(stroke
				(width 0.1)
				(type default)
			)
			(layer "F.Fab")
		)
		(pad "1" smd rect
			(at 0 0 90)
			(size 0.508 0.508)
			(layers "F.Cu" "F.Mask" "F.Paste")
			(net "P1V8_MCP_CPU1")
		)
		(pad "2" smd rect
			(at 0 0.889 90)
			(size 0.508 0.508)
			(layers "F.Cu" "F.Mask" "F.Paste")
			(net "GND")
		)
		(zone
			(layer "F.Cu")
			(hatch none 0.5)
			(connect_pads
				(clearance 0)
			)
			(min_thickness 0.25)
			(keepout
				(tracks allowed)
				(vias not_allowed)
				(pads allowed)
				(copperpour not_allowed)
				(footprints allowed)
			)
			(placement
				(enabled no)
				(sheetname "")
			)
			(fill
				(thermal_gap 0.5)
				(thermal_bridge_width 0.5)
				(island_removal_mode 0)
			)
			(polygon
				(pts
					(xy 167.26027 -33.8963) (xy 167.26027 -34.4043) (xy 167.64127 -34.4043) (xy 167.64127 -33.8963)
				)
			)
		)
		(zone
			(layer "F.Cu")
			(hatch none 0.5)
			(connect_pads
				(clearance 0)
			)
			(min_thickness 0.25)
			(keepout
				(tracks not_allowed)
				(vias allowed)
				(pads allowed)
				(copperpour not_allowed)
				(footprints allowed)
			)
			(placement
				(enabled no)
				(sheetname "")
			)
			(fill
				(thermal_gap 0.5)
				(thermal_bridge_width 0.5)
				(island_removal_mode 0)
			)
			(polygon
				(pts
					(xy 167.64127 -33.8963) (xy 167.64127 -34.4043) (xy 167.26027 -34.4043) (xy 167.26027 -33.8963)
				)
			)
		)
	)
)
